(kicad_pcb
	(version 20241229)
	(generator "pcbnew")
	(generator_version "9.0")
	(general
		(thickness 1.62)
		(legacy_teardrops no)
	)
	(paper "A3")
	(title_block
		(title "COM Express 7 Baseboard")
		(date "2025-02-04")
		(rev "1.1.2")
		(company "Antmicro Ltd")
		(comment 1 "www.antmicro.com")
		(comment 9 "footprints 28-32 of 802")
	)
	(layers
		(0 "F.Cu" signal)
		(4 "In1.Cu" signal)
		(6 "In2.Cu" signal)
		(8 "In3.Cu" signal)
		(10 "In4.Cu" signal)
		(12 "In5.Cu" signal)
		(14 "In6.Cu" signal)
		(2 "B.Cu" signal)
		(9 "F.Adhes" user "F.Adhesive")
		(11 "B.Adhes" user "B.Adhesive")
		(13 "F.Paste" user)
		(15 "B.Paste" user)
		(5 "F.SilkS" user "F.Silkscreen")
		(7 "B.SilkS" user "B.Silkscreen")
		(1 "F.Mask" user)
		(3 "B.Mask" user)
		(17 "Dwgs.User" user "User.Drawings")
		(19 "Cmts.User" user "User.Comments")
		(21 "Eco1.User" user "User.Eco1")
		(23 "Eco2.User" user "User.Eco2")
		(25 "Edge.Cuts" user)
		(27 "Margin" user)
		(31 "F.CrtYd" user "F.Courtyard")
		(29 "B.CrtYd" user "B.Courtyard")
		(35 "F.Fab" user)
		(33 "B.Fab" user)
	)
	(footprint "antmicro-footprints:TP_SMD_0.75mm"
		(layer "F.Cu")
		(at 197.875 133.7 45)
		(property "Reference" "TP55"
			(at 0.45 0.499999 45)
			(layer "F.SilkS")
			(effects
				(font
					(size 0.7 0.7)
					(thickness 0.15)
				)
				(justify left bottom)
			)
		)
		(property "Value" "TP_0.75mm_SMD"
			(at 0 1.2 45)
			(layer "F.Fab")
			(effects
				(font
					(size 0.7 0.7)
					(thickness 0.15)
				)
				(justify left bottom)
			)
		)
		(property "Author" "Antmicro"
			(at 369.6 -273.32 45)
			(layer "F.Fab")
			(hide yes)
			(effects
				(font
					(size 1 1)
					(thickness 0.15)
				)
			)
		)
		(property "License" "Apache-2.0"
			(at 369.6 -273.32 45)
			(layer "F.Fab")
			(hide yes)
			(effects
				(font
					(size 1 1)
					(thickness 0.15)
				)
			)
		)
		(property "MPN" ""
			(at 369.6 -273.32 45)
			(layer "F.Fab")
			(hide yes)
			(effects
				(font
					(size 1 1)
					(thickness 0.15)
				)
			)
		)
		(property "Manufacturer" ""
			(at 369.6 -273.32 45)
			(layer "F.Fab")
			(hide yes)
			(effects
				(font
					(size 1 1)
					(thickness 0.15)
				)
			)
		)
		(property "Public" "False"
			(at 369.6 -273.32 45)
			(layer "F.Fab")
			(hide yes)
			(effects
				(font
					(size 1 1)
					(thickness 0.15)
				)
			)
		)
		(sheetname "PCIe redriver")
		(sheetfile "pcie_redriver.kicad_sch")
		(attr exclude_from_pos_files exclude_from_bom)
		(fp_circle
			(center 0 0)
			(end 0.475 0)
			(stroke
				(width 0.05)
				(type default)
			)
			(fill no)
			(layer "F.CrtYd")
		)
		(pad "1" smd circle
			(at 0 0 45)
			(size 0.75 0.75)
			(layers "F.Cu" "F.Mask")
			(net 718 "Net-(U40-I2C_{DONE})")
			(pinfunction "1")
			(pintype "passive")
			(teardrops
				(best_length_ratio 0.4)
				(max_length 1)
				(best_width_ratio 0.9)
				(max_width 2)
				(curved_edges yes)
				(filter_ratio 0.9)
				(enabled yes)
				(allow_two_segments yes)
				(prefer_zone_connections yes)
			)
		)
	)
	(footprint "antmicro-footprints:R_0402_1005Metric"
		(layer "F.Cu")
		(at 177.52 107.66 180)
		(descr "Resistor SMD 0402")
		(tags "resistor SMD 0402")
		(property "Reference" "R120"
			(at 0.82 -0.45 0)
			(layer "F.SilkS")
			(effects
				(font
					(size 0.7 0.7)
					(thickness 0.15)
				)
				(justify right bottom)
			)
		)
		(property "Value" "R_0R_0402"
			(at -1.011843 1.772047 0)
			(layer "F.Fab")
			(effects
				(font
					(size 0.7 0.7)
					(thickness 0.15)
				)
				(justify right bottom)
			)
		)
		(property "Datasheet" "https://industrial.panasonic.com/cdbs/www-data/pdf/RDA0000/AOA0000C301.pdf"
			(at 0 0 180)
			(layer "F.Fab")
			(hide yes)
			(effects
				(font
					(size 1.27 1.27)
					(thickness 0.15)
				)
			)
		)
		(property "Author" "Antmicro"
			(at 355.04 215.32 0)
			(layer "F.Fab")
			(hide yes)
			(effects
				(font
					(size 1 1)
					(thickness 0.15)
				)
			)
		)
		(property "Current" "1A"
			(at 355.04 215.32 0)
			(layer "F.Fab")
			(hide yes)
			(effects
				(font
					(size 1 1)
					(thickness 0.15)
				)
			)
		)
		(property "License" "Apache-2.0"
			(at 355.04 215.32 0)
			(layer "F.Fab")
			(hide yes)
			(effects
				(font
					(size 1 1)
					(thickness 0.15)
				)
			)
		)
		(property "MPN" "ERJ2GE0R00X"
			(at 355.04 215.32 0)
			(layer "F.Fab")
			(hide yes)
			(effects
				(font
					(size 1 1)
					(thickness 0.15)
				)
			)
		)
		(property "Manufacturer" "Panasonic"
			(at 355.04 215.32 0)
			(layer "F.Fab")
			(hide yes)
			(effects
				(font
					(size 1 1)
					(thickness 0.15)
				)
			)
		)
		(property "Public" "False"
			(at 355.04 215.32 0)
			(layer "F.Fab")
			(hide yes)
			(effects
				(font
					(size 1 1)
					(thickness 0.15)
				)
			)
		)
		(property "Tolerance" ""
			(at 355.04 215.32 0)
			(layer "F.Fab")
			(hide yes)
			(effects
				(font
					(size 1 1)
					(thickness 0.15)
				)
			)
		)
		(property "Val" "0R"
			(at 355.04 215.32 0)
			(layer "F.Fab")
			(hide yes)
			(effects
				(font
					(size 1 1)
					(thickness 0.15)
				)
			)
		)
		(sheetname "M.2 key M #1")
		(sheetfile "m2keym_low.kicad_sch")
		(attr smd)
		(fp_rect
			(start -0.925 -0.47)
			(end 0.925 0.47)
			(stroke
				(width 0.05)
				(type default)
			)
			(fill no)
			(layer "F.CrtYd")
		)
		(fp_rect
			(start -0.5 -0.25)
			(end 0.5 0.25)
			(stroke
				(width 0.15)
				(type solid)
			)
			(fill no)
			(layer "F.Fab")
		)
		(pad "1" smd roundrect
			(at -0.48 0 180)
			(size 0.59 0.64)
			(layers "F.Cu" "F.Mask" "F.Paste")
			(roundrect_rratio 0.25)
			(net 528 "/Backplane/~{PERST}")
			(pintype "passive")
			(teardrops
				(best_length_ratio 0.2)
				(max_length 1)
				(best_width_ratio 0.9)
				(max_width 2)
				(curved_edges yes)
				(filter_ratio 0.9)
				(enabled yes)
				(allow_two_segments yes)
				(prefer_zone_connections yes)
			)
		)
		(pad "2" smd roundrect
			(at 0.48 0 180)
			(size 0.59 0.64)
			(layers "F.Cu" "F.Mask" "F.Paste")
			(roundrect_rratio 0.25)
			(net 228 "/M.2 key M #1/~{PERST_D}")
			(pintype "passive")
			(teardrops
				(best_length_ratio 0.2)
				(max_length 1)
				(best_width_ratio 0.9)
				(max_width 2)
				(curved_edges yes)
				(filter_ratio 0.9)
				(enabled yes)
				(allow_two_segments yes)
				(prefer_zone_connections yes)
			)
		)
	)
	(footprint "antmicro-footprints:R_0402_1005Metric"
		(layer "F.Cu")
		(at 306.14 130.03)
		(descr "Resistor SMD 0402")
		(tags "resistor SMD 0402")
		(property "Reference" "R101"
			(at -1.14 -0.52 0)
			(layer "F.SilkS")
			(effects
				(font
					(size 0.7 0.7)
					(thickness 0.15)
				)
				(justify left bottom)
			)
		)
		(property "Value" "R_100k_0402"
			(at -1.011843 1.772047 0)
			(layer "F.Fab")
			(effects
				(font
					(size 0.7 0.7)
					(thickness 0.15)
				)
				(justify left bottom)
			)
		)
		(property "Datasheet" "https://www.bourns.com/docs/product-datasheets/cr.pdf"
			(at 0 0 0)
			(layer "F.Fab")
			(hide yes)
			(effects
				(font
					(size 1.27 1.27)
					(thickness 0.15)
				)
			)
		)
		(property "Author" "Antmicro"
			(at 0 0 0)
			(layer "F.Fab")
			(hide yes)
			(effects
				(font
					(size 1 1)
					(thickness 0.15)
				)
			)
		)
		(property "License" "Apache-2.0"
			(at 0 0 0)
			(layer "F.Fab")
			(hide yes)
			(effects
				(font
					(size 1 1)
					(thickness 0.15)
				)
			)
		)
		(property "MPN" "CR0402-FX-1003GLF"
			(at 0 0 0)
			(layer "F.Fab")
			(hide yes)
			(effects
				(font
					(size 1 1)
					(thickness 0.15)
				)
			)
		)
		(property "Manufacturer" "Bourns"
			(at 0 0 0)
			(layer "F.Fab")
			(hide yes)
			(effects
				(font
					(size 1 1)
					(thickness 0.15)
				)
			)
		)
		(property "Public" "False"
			(at 0 0 0)
			(layer "F.Fab")
			(hide yes)
			(effects
				(font
					(size 1 1)
					(thickness 0.15)
				)
			)
		)
		(property "Tolerance" "1%"
			(at 0 0 0)
			(layer "F.Fab")
			(hide yes)
			(effects
				(font
					(size 1 1)
					(thickness 0.15)
				)
			)
		)
		(property "Val" "100k"
			(at 0 0 0)
			(layer "F.Fab")
			(hide yes)
			(effects
				(font
					(size 1 1)
					(thickness 0.15)
				)
			)
		)
		(sheetname "Power")
		(sheetfile "power.kicad_sch")
		(attr smd)
		(fp_rect
			(start -0.925 -0.47)
			(end 0.925 0.47)
			(stroke
				(width 0.05)
				(type default)
			)
			(fill no)
			(layer "F.CrtYd")
		)
		(fp_rect
			(start -0.5 -0.25)
			(end 0.5 0.25)
			(stroke
				(width 0.15)
				(type solid)
			)
			(fill no)
			(layer "F.Fab")
		)
		(pad "1" smd roundrect
			(at -0.48 0)
			(size 0.59 0.64)
			(layers "F.Cu" "F.Mask" "F.Paste")
			(roundrect_rratio 0.25)
			(net 1 "GND")
			(pintype "passive")
			(teardrops
				(best_length_ratio 0.2)
				(max_length 1)
				(best_width_ratio 0.9)
				(max_width 2)
				(curved_edges yes)
				(filter_ratio 0.9)
				(enabled yes)
				(allow_two_segments yes)
				(prefer_zone_connections yes)
			)
		)
		(pad "2" smd roundrect
			(at 0.48 0)
			(size 0.59 0.64)
			(layers "F.Cu" "F.Mask" "F.Paste")
			(roundrect_rratio 0.25)
			(net 578 "/Power/PG_{1V0}")
			(pintype "passive")
			(teardrops
				(best_length_ratio 0.2)
				(max_length 1)
				(best_width_ratio 0.9)
				(max_width 2)
				(curved_edges yes)
				(filter_ratio 0.9)
				(enabled yes)
				(allow_two_segments yes)
				(prefer_zone_connections yes)
			)
		)
	)
	(footprint "antmicro-footprints:USON-10_2.5x1mm_P0.5mm"
		(layer "F.Cu")
		(at 110.7 152.2 -90)
		(descr "USON-10 2.5x1mm_ Pitch 0.5mm")
		(tags "USON-10 2.5x1mm Pitch 0.5mm")
		(property "Reference" "U17"
			(at -1.7 1.3 0)
			(layer "F.SilkS")
			(effects
				(font
					(size 0.7 0.7)
					(thickness 0.15)
				)
				(justify left top)
			)
		)
		(property "Value" "ESD204DQAR"
			(at 0.018 2.499 90)
			(layer "F.Fab")
			(effects
				(font
					(size 0.7 0.7)
					(thickness 0.15)
				)
				(justify right bottom)
			)
		)
		(property "Datasheet" "https://www.ti.com/lit/ds/symlink/esd204.pdf?ts=1706004844383&ref_url=https%253A%252F%252Fwww.ti.com%252Finterface%252Fdiodes%252Fesd-protection-diodes%252Fproducts.html"
			(at 0 0 90)
			(layer "F.Fab")
			(hide yes)
			(effects
				(font
					(size 1.27 1.27)
					(thickness 0.15)
				)
			)
		)
		(property "Author" "Antmicro"
			(at -46.422998 258.252998 0)
			(layer "F.Fab")
			(hide yes)
			(effects
				(font
					(size 1 1)
					(thickness 0.15)
				)
			)
		)
		(property "License" "Apache-2.0"
			(at -46.422998 258.252998 0)
			(layer "F.Fab")
			(hide yes)
			(effects
				(font
					(size 1 1)
					(thickness 0.15)
				)
			)
		)
		(property "MPN" "ESD204DQAR"
			(at -46.422998 258.252998 0)
			(layer "F.Fab")
			(hide yes)
			(effects
				(font
					(size 1 1)
					(thickness 0.15)
				)
			)
		)
		(property "Manufacturer" "Texas Instruments"
			(at -46.422998 258.252998 0)
			(layer "F.Fab")
			(hide yes)
			(effects
				(font
					(size 1 1)
					(thickness 0.15)
				)
			)
		)
		(sheetname "OCuLink")
		(sheetfile "oculink.kicad_sch")
		(attr smd)
		(fp_line
			(start 0.498 1.398)
			(end -0.5 1.398)
			(stroke
				(width 0.15)
				(type solid)
			)
			(layer "F.SilkS")
		)
		(fp_line
			(start 0.498 -1.401)
			(end -0.5 -1.401)
			(stroke
				(width 0.15)
				(type solid)
			)
			(layer "F.SilkS")
		)
		(fp_circle
			(center -0.68 -1.27)
			(end -0.63 -1.27)
			(stroke
				(width 0.15)
				(type solid)
			)
			(fill yes)
			(layer "F.SilkS")
		)
		(fp_rect
			(start -0.8 -1.5)
			(end 0.8 1.499)
			(stroke
				(width 0.05)
				(type solid)
			)
			(fill no)
			(layer "F.CrtYd")
		)
		(fp_line
			(start -0.5 1.249)
			(end 0.498 1.249)
			(stroke
				(width 0.15)
				(type solid)
			)
			(layer "F.Fab")
		)
		(fp_line
			(start -0.5 -1)
			(end -0.5 1.249)
			(stroke
				(width 0.15)
				(type solid)
			)
			(layer "F.Fab")
		)
		(fp_line
			(start -0.25 -1.25)
			(end -0.5 -1)
			(stroke
				(width 0.15)
				(type solid)
			)
			(layer "F.Fab")
		)
		(fp_line
			(start 0.498 -1.25)
			(end 0.498 1.249)
			(stroke
				(width 0.15)
				(type solid)
			)
			(layer "F.Fab")
		)
		(fp_line
			(start 0.498 -1.25)
			(end -0.25 -1.25)
			(stroke
				(width 0.15)
				(type solid)
			)
			(layer "F.Fab")
		)
		(pad "1" smd roundrect
			(at -0.387 -1 180)
			(size 0.25 0.55)
			(layers "F.Cu" "F.Mask" "F.Paste")
			(roundrect_rratio 0.25)
			(net 192 "/OCuLink/PCIe_{REF0}.CK+")
			(pintype "passive")
			(teardrops
				(best_length_ratio 0.2)
				(max_length 1)
				(best_width_ratio 0.9)
				(max_width 2)
				(curved_edges yes)
				(filter_ratio 0.9)
				(enabled yes)
				(allow_two_segments yes)
				(prefer_zone_connections yes)
			)
		)
		(pad "2" smd roundrect
			(at -0.387 -0.5 180)
			(size 0.25 0.55)
			(layers "F.Cu" "F.Mask" "F.Paste")
			(roundrect_rratio 0.25)
			(net 193 "/OCuLink/PCIe_{REF0}.CK-")
			(pintype "passive")
			(teardrops
				(best_length_ratio 0.2)
				(max_length 1)
				(best_width_ratio 0.9)
				(max_width 2)
				(curved_edges yes)
				(filter_ratio 0.9)
				(enabled yes)
				(allow_two_segments yes)
				(prefer_zone_connections yes)
			)
		)
		(pad "3" smd roundrect
			(at -0.387 0 180)
			(size 0.4 0.55)
			(layers "F.Cu" "F.Mask" "F.Paste")
			(roundrect_rratio 0.25)
			(net 1 "GND")
			(pintype "power_in")
			(teardrops
				(best_length_ratio 0.2)
				(max_length 1)
				(best_width_ratio 0.9)
				(max_width 2)
				(curved_edges yes)
				(filter_ratio 0.9)
				(enabled yes)
				(allow_two_segments yes)
				(prefer_zone_connections yes)
			)
		)
		(pad "4" smd roundrect
			(at -0.387 0.498 180)
			(size 0.25 0.55)
			(layers "F.Cu" "F.Mask" "F.Paste")
			(roundrect_rratio 0.25)
			(net 996 "unconnected-(U17-Pad4)_1")
			(pintype "passive+no_connect")
			(teardrops
				(best_length_ratio 0.2)
				(max_length 1)
				(best_width_ratio 0.9)
				(max_width 2)
				(curved_edges yes)
				(filter_ratio 0.9)
				(enabled yes)
				(allow_two_segments yes)
				(prefer_zone_connections yes)
			)
		)
		(pad "5" smd roundrect
			(at -0.387 0.998 180)
			(size 0.25 0.55)
			(layers "F.Cu" "F.Mask" "F.Paste")
			(roundrect_rratio 0.25)
			(net 992 "unconnected-(U17-Pad5)")
			(pintype "passive+no_connect")
			(teardrops
				(best_length_ratio 0.2)
				(max_length 1)
				(best_width_ratio 0.9)
				(max_width 2)
				(curved_edges yes)
				(filter_ratio 0.9)
				(enabled yes)
				(allow_two_segments yes)
				(prefer_zone_connections yes)
			)
		)
		(pad "6" smd roundrect
			(at 0.385 0.998 180)
			(size 0.25 0.55)
			(layers "F.Cu" "F.Mask" "F.Paste")
			(roundrect_rratio 0.25)
			(net 997 "unconnected-(U17-Pad5)_1")
			(pintype "passive+no_connect")
			(teardrops
				(best_length_ratio 0.2)
				(max_length 1)
				(best_width_ratio 0.9)
				(max_width 2)
				(curved_edges yes)
				(filter_ratio 0.9)
				(enabled yes)
				(allow_two_segments yes)
				(prefer_zone_connections yes)
			)
		)
		(pad "7" smd roundrect
			(at 0.385 0.498 180)
			(size 0.25 0.55)
			(layers "F.Cu" "F.Mask" "F.Paste")
			(roundrect_rratio 0.25)
			(net 991 "unconnected-(U17-Pad4)")
			(pintype "passive+no_connect")
			(teardrops
				(best_length_ratio 0.2)
				(max_length 1)
				(best_width_ratio 0.9)
				(max_width 2)
				(curved_edges yes)
				(filter_ratio 0.9)
				(enabled yes)
				(allow_two_segments yes)
				(prefer_zone_connections yes)
			)
		)
		(pad "8" smd roundrect
			(at 0.385 0 180)
			(size 0.4 0.55)
			(layers "F.Cu" "F.Mask" "F.Paste")
			(roundrect_rratio 0.25)
			(net 1 "GND")
			(pintype "passive")
			(teardrops
				(best_length_ratio 0.2)
				(max_length 1)
				(best_width_ratio 0.9)
				(max_width 2)
				(curved_edges yes)
				(filter_ratio 0.9)
				(enabled yes)
				(allow_two_segments yes)
				(prefer_zone_connections yes)
			)
		)
		(pad "9" smd roundrect
			(at 0.385 -0.5 180)
			(size 0.25 0.55)
			(layers "F.Cu" "F.Mask" "F.Paste")
			(roundrect_rratio 0.25)
			(net 193 "/OCuLink/PCIe_{REF0}.CK-")
			(pintype "passive")
			(teardrops
				(best_length_ratio 0.2)
				(max_length 1)
				(best_width_ratio 0.9)
				(max_width 2)
				(curved_edges yes)
				(filter_ratio 0.9)
				(enabled yes)
				(allow_two_segments yes)
				(prefer_zone_connections yes)
			)
		)
		(pad "10" smd roundrect
			(at 0.385 -1 180)
			(size 0.25 0.55)
			(layers "F.Cu" "F.Mask" "F.Paste")
			(roundrect_rratio 0.25)
			(net 192 "/OCuLink/PCIe_{REF0}.CK+")
			(pintype "passive")
			(teardrops
				(best_length_ratio 0.2)
				(max_length 1)
				(best_width_ratio 0.9)
				(max_width 2)
				(curved_edges yes)
				(filter_ratio 0.9)
				(enabled yes)
				(allow_two_segments yes)
				(prefer_zone_connections yes)
			)
		)
	)
	(footprint "antmicro-footprints:R_0402_1005Metric"
		(layer "F.Cu")
		(at 190.054908 138.772113 -135)
		(descr "Resistor SMD 0402")
		(tags "resistor SMD 0402")
		(property "Reference" "R228"
			(at 1.069206 -0.415818 45)
			(layer "F.SilkS")
			(effects
				(font
					(size 0.7 0.7)
					(thickness 0.15)
				)
				(justify right bottom)
			)
		)
		(property "Value" "R_1k_0402"
			(at -1.011843 1.772046 45)
			(layer "F.Fab")
			(effects
				(font
					(size 0.7 0.7)
					(thickness 0.15)
				)
				(justify right bottom)
			)
		)
		(property "Datasheet" "https://www.bourns.com/docs/product-datasheets/cr.pdf"
			(at 0 0 45)
			(layer "B.Fab")
			(hide yes)
			(effects
				(font
					(size 1.27 1.27)
					(thickness 0.15)
				)
				(justify mirror)
			)
		)
		(property "Author" "Antmicro"
			(at 0 0 45)
			(layer "F.Fab")
			(hide yes)
			(effects
				(font
					(size 1 1)
					(thickness 0.15)
				)
			)
		)
		(property "License" "Apache-2.0"
			(at 0 0 45)
			(layer "F.Fab")
			(hide yes)
			(effects
				(font
					(size 1 1)
					(thickness 0.15)
				)
			)
		)
		(property "MPN" "CR0402-FX-1001GLF"
			(at 0 0 45)
			(layer "F.Fab")
			(hide yes)
			(effects
				(font
					(size 1 1)
					(thickness 0.15)
				)
			)
		)
		(property "Manufacturer" "Bourns"
			(at 0 0 45)
			(layer "F.Fab")
			(hide yes)
			(effects
				(font
					(size 1 1)
					(thickness 0.15)
				)
			)
		)
		(property "Public" "False"
			(at 0 0 45)
			(layer "F.Fab")
			(hide yes)
			(effects
				(font
					(size 1 1)
					(thickness 0.15)
				)
			)
		)
		(property "Tolerance" "1%"
			(at 0 0 45)
			(layer "F.Fab")
			(hide yes)
			(effects
				(font
					(size 1 1)
					(thickness 0.15)
				)
			)
		)
		(property "Val" "1k"
			(at 0 0 45)
			(layer "F.Fab")
			(hide yes)
			(effects
				(font
					(size 1 1)
					(thickness 0.15)
				)
			)
		)
		(sheetname "PCIe redriver")
		(sheetfile "pcie_redriver.kicad_sch")
		(attr smd)
		(fp_poly
			(pts
				(xy -0.925 -0.47) (xy 0.925 -0.47) (xy 0.925 0.47) (xy -0.925 0.47)
			)
			(stroke
				(width 0.05)
				(type default)
			)
			(fill no)
			(layer "F.CrtYd")
		)
		(fp_poly
			(pts
				(xy -0.5 -0.25) (xy 0.5 -0.25) (xy 0.5 0.25) (xy -0.5 0.25)
			)
			(stroke
				(width 0.15)
				(type solid)
			)
			(fill no)
			(layer "F.Fab")
		)
		(pad "1" smd roundrect
			(at -0.48 0 225)
			(size 0.59 0.64)
			(layers "F.Cu" "F.Mask" "F.Paste")
			(roundrect_rratio 0.25)
			(net 1 "GND")
			(pintype "passive")
			(teardrops
				(best_length_ratio 0.2)
				(max_length 1)
				(best_width_ratio 0.9)
				(max_width 2)
				(curved_edges yes)
				(filter_ratio 0.9)
				(enabled yes)
				(allow_two_segments yes)
				(prefer_zone_connections yes)
			)
		)
		(pad "2" smd roundrect
			(at 0.48 0 225)
			(size 0.59 0.64)
			(layers "F.Cu" "F.Mask" "F.Paste")
			(roundrect_rratio 0.25)
			(net 977 "/PCIe redriver/RX_EQ1")
			(pintype "passive")
			(teardrops
				(best_length_ratio 0.2)
				(max_length 1)
				(best_width_ratio 0.9)
				(max_width 2)
				(curved_edges yes)
				(filter_ratio 0.9)
				(enabled yes)
				(allow_two_segments yes)
				(prefer_zone_connections yes)
			)
		)
	)
)
